# BASEBOARD_FAB2 (Tioga Pass) — schematic netlist excerpt (pin names and nets, part order shuffled) for the footprints in the layout excerpt that follows; sources: Cadence DE-HDL packaged netlist, KiCad conversion of Wiwynn_Tioga_Pass_MB.brd

C6P19  CAP  10UF 16V 10% X6S  pkg 0805  page 203 : A = VR_FET_SW_P12V_STBY_PVCCIN_CPU0 ; B = GND
R781  RES  0.0 5% CHIP  pkg 0402  page 244 : A = P3E_CPU0_PE1_PCH_RXP<10> ; B = P3E_CPU0_PE1_PCH_CON_RXP<10>
C5L4  CAP  100UF 4V 20% X5R  pkg 0805  page 222 : A = PVTT_DEF ; B = GND

(kicad_pcb
	(version 20260206)
	(generator "pcbnew")
	(generator_version "10.0")
	(general
		(thickness 1.6)
		(legacy_teardrops no)
	)
	(paper "A4")
	(title_block
		(title "Wiwynn_Tioga_Pass_MB.brd")
		(comment 1 "Tioga Pass / footprints 4438-4440 of 4770")
	)
	(layers
		(0 "F.Cu" signal "TOP")
		(4 "In1.Cu" signal "L2GND")
		(6 "In2.Cu" signal "L3")
		(8 "In3.Cu" signal "L4GND")
		(10 "In4.Cu" signal "L5")
		(12 "In5.Cu" signal "L6GND")
		(14 "In6.Cu" signal "L7VCC")
		(16 "In7.Cu" signal "L8VCC")
		(18 "In8.Cu" signal "L9GND")
		(20 "In9.Cu" signal "L10")
		(22 "In10.Cu" signal "L11GND")
		(24 "In11.Cu" signal "L12")
		(26 "In12.Cu" signal "L13GND")
		(2 "B.Cu" signal "BOTTOM")
		(9 "F.Adhes" user "F.Adhesive")
		(11 "B.Adhes" user "B.Adhesive")
		(13 "F.Paste" user "Package Geometry/Pastemask Top")
		(15 "B.Paste" user "Package Geometry/Pastemask Bottom")
		(5 "F.SilkS" user "Ref Des/Silkscreen Top")
		(7 "B.SilkS" user "Ref Des/Silkscreen Bottom")
		(1 "F.Mask" user "Board Geometry/Soldermask Top")
		(3 "B.Mask" user "Board Geometry/Soldermask Bottom")
		(17 "Dwgs.User" user "User.Drawings")
		(19 "Cmts.User" user "User.Comments")
		(21 "Eco1.User" user "User.Eco1")
		(23 "Eco2.User" user "User.Eco2")
		(25 "Edge.Cuts" user "Board Geometry/Outline")
		(27 "Margin" user)
		(31 "F.CrtYd" user "Package Geometry/Place Bound Top")
		(29 "B.CrtYd" user "Package Geometry/Place Bound Bottom")
		(35 "F.Fab" user "Ref Des/Assembly Top")
		(33 "B.Fab" user "Ref Des/Assembly Bottom")
	)
	(footprint ""
		(layer "B.Cu")
		(at 256.853436 -157.016958 90)
		(property "Reference" "C5L4"
			(at -1.47828 0.78994 180)
			(unlocked yes)
			(layer "B.SilkS")
			(effects
				(font
					(size 0.4064 0.254)
					(thickness 0.1524)
				)
				(justify mirror)
			)
		)
		(property "Value" ""
			(at 0 0 90)
			(layer "B.Fab")
			(effects
				(font
					(size 1.27 1.27)
				)
				(justify mirror)
			)
		)
		(duplicate_pad_numbers_are_jumpers no)
		(fp_poly
			(pts
				(xy 0.7239 -0.2159) (xy -0.7239 -0.2159) (xy -0.7239 1.9939) (xy 0.7239 1.9939)
			)
			(stroke
				(width 0)
				(type default)
			)
			(fill no)
			(layer "B.CrtYd")
		)
		(fp_line
			(start 0.7239 -0.2159)
			(end 0.7239 1.9939)
			(stroke
				(width 0.1)
				(type default)
			)
			(layer "B.Fab")
		)
		(fp_line
			(start -0.7239 -0.2159)
			(end 0.7239 -0.2159)
			(stroke
				(width 0.1)
				(type default)
			)
			(layer "B.Fab")
		)
		(fp_line
			(start 0.7239 1.9939)
			(end -0.7239 1.9939)
			(stroke
				(width 0.1)
				(type default)
			)
			(layer "B.Fab")
		)
		(fp_line
			(start -0.7239 1.9939)
			(end -0.7239 -0.2159)
			(stroke
				(width 0.1)
				(type default)
			)
			(layer "B.Fab")
		)
		(pad "1" smd rect
			(at 0 0 270)
			(size 1.27 1.016)
			(layers "B.Cu" "B.Mask" "B.Paste")
			(net "PVTT_DEF")
		)
		(pad "2" smd rect
			(at 0 1.778 270)
			(size 1.27 1.016)
			(layers "B.Cu" "B.Mask" "B.Paste")
			(net "GND")
		)
		(zone
			(layer "B.Cu")
			(hatch none 0.5)
			(connect_pads
				(clearance 0)
			)
			(min_thickness 0.25)
			(keepout
				(tracks not_allowed)
				(vias allowed)
				(pads allowed)
				(copperpour not_allowed)
				(footprints allowed)
			)
			(placement
				(enabled no)
				(sheetname "")
			)
			(fill
				(thermal_gap 0.5)
				(thermal_bridge_width 0.5)
				(island_removal_mode 0)
			)
			(polygon
				(pts
					(xy 257.361436 -157.651958) (xy 257.361436 -156.381958) (xy 258.123436 -156.381958) (xy 258.123436 -157.651958)
				)
			)
		)
	)
	(footprint ""
		(layer "B.Cu")
		(at 361.782614 -125.558042 -90)
		(property "Reference" "R781"
			(at 0.8382 -0.67818 270)
			(unlocked yes)
			(layer "B.SilkS")
			(effects
				(font
					(size 0.4064 0.254)
					(thickness 0.1524)
				)
				(justify left mirror)
			)
		)
		(property "Value" ""
			(at 0 0 90)
			(layer "B.Fab")
			(effects
				(font
					(size 1.27 1.27)
				)
				(justify mirror)
			)
		)
		(duplicate_pad_numbers_are_jumpers no)
		(fp_poly
			(pts
				(xy 0.2794 -0.1016) (xy -0.2794 -0.1016) (xy -0.2794 0.9906) (xy 0.2794 0.9906)
			)
			(stroke
				(width 0)
				(type default)
			)
			(fill no)
			(layer "B.CrtYd")
		)
		(fp_line
			(start -0.2794 0.9906)
			(end -0.2794 -0.1016)
			(stroke
				(width 0.1)
				(type default)
			)
			(layer "B.Fab")
		)
		(fp_line
			(start 0.2794 0.9906)
			(end -0.2794 0.9906)
			(stroke
				(width 0.1)
				(type default)
			)
			(layer "B.Fab")
		)
		(fp_line
			(start -0.2794 -0.1016)
			(end 0.2794 -0.1016)
			(stroke
				(width 0.1)
				(type default)
			)
			(layer "B.Fab")
		)
		(fp_line
			(start 0.2794 -0.1016)
			(end 0.2794 0.9906)
			(stroke
				(width 0.1)
				(type default)
			)
			(layer "B.Fab")
		)
		(pad "1" smd rect
			(at 0 0 90)
			(size 0.508 0.508)
			(layers "B.Cu" "B.Mask" "B.Paste")
			(net "P3E_CPU0_PE1_PCH_RXP<10>")
		)
		(pad "2" smd rect
			(at 0 0.889 90)
			(size 0.508 0.508)
			(layers "B.Cu" "B.Mask" "B.Paste")
			(net "P3E_CPU0_PE1_PCH_CON_RXP<10>")
		)
		(zone
			(layer "B.Cu")
			(hatch none 0.5)
			(connect_pads
				(clearance 0)
			)
			(min_thickness 0.25)
			(keepout
				(tracks not_allowed)
				(vias allowed)
				(pads allowed)
				(copperpour not_allowed)
				(footprints allowed)
			)
			(placement
				(enabled no)
				(sheetname "")
			)
			(fill
				(thermal_gap 0.5)
				(thermal_bridge_width 0.5)
				(island_removal_mode 0)
			)
			(polygon
				(pts
					(xy 361.147614 -125.304042) (xy 361.147614 -125.812042) (xy 361.528614 -125.812042) (xy 361.528614 -125.304042)
				)
			)
		)
		(zone
			(layer "B.Cu")
			(hatch none 0.5)
			(connect_pads
				(clearance 0)
			)
			(min_thickness 0.25)
			(keepout
				(tracks allowed)
				(vias not_allowed)
				(pads allowed)
				(copperpour not_allowed)
				(footprints allowed)
			)
			(placement
				(enabled no)
				(sheetname "")
			)
			(fill
				(thermal_gap 0.5)
				(thermal_bridge_width 0.5)
				(island_removal_mode 0)
			)
			(polygon
				(pts
					(xy 361.528614 -125.304042) (xy 361.528614 -125.812042) (xy 361.147614 -125.812042) (xy 361.147614 -125.304042)
				)
			)
		)
	)
	(footprint ""
		(layer "B.Cu")
		(at 197.848728 -74.506582 90)
		(property "Reference" "C6P19"
			(at 0 0 90)
			(layer "B.SilkS")
			(hide yes)
			(effects
				(font
					(size 1.27 1.27)
				)
				(justify mirror)
			)
		)
		(property "Value" ""
			(at 0 0 90)
			(layer "B.Fab")
			(effects
				(font
					(size 1.27 1.27)
				)
				(justify mirror)
			)
		)
		(duplicate_pad_numbers_are_jumpers no)
		(fp_rect
			(start 0.7239 1.9939)
			(end -0.7239 -0.2159)
			(stroke
				(width 0)
				(type default)
			)
			(fill no)
			(layer "B.CrtYd")
		)
		(fp_line
			(start 0.7239 -0.2159)
			(end 0.7239 1.9939)
			(stroke
				(width 0.1)
				(type default)
			)
			(layer "B.Fab")
		)
		(fp_line
			(start -0.7239 -0.2159)
			(end 0.7239 -0.2159)
			(stroke
				(width 0.1)
				(type default)
			)
			(layer "B.Fab")
		)
		(fp_line
			(start 0.7239 1.9939)
			(end -0.7239 1.9939)
			(stroke
				(width 0.1)
				(type default)
			)
			(layer "B.Fab")
		)
		(fp_line
			(start -0.7239 1.9939)
			(end -0.7239 -0.2159)
			(stroke
				(width 0.1)
				(type default)
			)
			(layer "B.Fab")
		)
		(pad "1" smd rect
			(at 0 0 270)
			(size 1.27 1.016)
			(layers "B.Cu" "B.Mask" "B.Paste")
			(net "VR_FET_SW_P12V_STBY_PVCCIN_CPU0")
		)
		(pad "2" smd rect
			(at 0 1.778 270)
			(size 1.27 1.016)
			(layers "B.Cu" "B.Mask" "B.Paste")
			(net "GND")
		)
		(zone
			(layer "B.Cu")
			(hatch none 0.5)
			(connect_pads
				(clearance 0)
			)
			(min_thickness 0.25)
			(keepout
				(tracks not_allowed)
				(vias allowed)
				(pads allowed)
				(copperpour not_allowed)
				(footprints allowed)
			)
			(placement
				(enabled no)
				(sheetname "")
			)
			(fill
				(thermal_gap 0.5)
				(thermal_bridge_width 0.5)
				(island_removal_mode 0)
			)
			(polygon
				(pts
					(xy 199.118728 -75.141582) (xy 198.356728 -75.141582) (xy 198.356728 -73.871582) (xy 199.118728 -73.871582)
				)
			)
		)
	)
)
